(kicad_pcb
	(version 20260206)
	(generator "pcbnew")
	(generator_version "10.0")
	(general
		(thickness 1.6)
		(legacy_teardrops no)
	)
	(paper "A4")
	(title_block
		(title "Wiwynn_Tioga_Pass_MB.brd")
		(comment 1 "Tioga Pass / footprints 1280-1286 of 4770")
	)
	(layers
		(0 "F.Cu" signal "TOP")
		(4 "In1.Cu" signal "L2GND")
		(6 "In2.Cu" signal "L3")
		(8 "In3.Cu" signal "L4GND")
		(10 "In4.Cu" signal "L5")
		(12 "In5.Cu" signal "L6GND")
		(14 "In6.Cu" signal "L7VCC")
		(16 "In7.Cu" signal "L8VCC")
		(18 "In8.Cu" signal "L9GND")
		(20 "In9.Cu" signal "L10")
		(22 "In10.Cu" signal "L11GND")
		(24 "In11.Cu" signal "L12")
		(26 "In12.Cu" signal "L13GND")
		(2 "B.Cu" signal "BOTTOM")
		(9 "F.Adhes" user "F.Adhesive")
		(11 "B.Adhes" user "B.Adhesive")
		(13 "F.Paste" user "Package Geometry/Pastemask Top")
		(15 "B.Paste" user "Package Geometry/Pastemask Bottom")
		(5 "F.SilkS" user "Ref Des/Silkscreen Top")
		(7 "B.SilkS" user "Ref Des/Silkscreen Bottom")
		(1 "F.Mask" user "Board Geometry/Soldermask Top")
		(3 "B.Mask" user "Board Geometry/Soldermask Bottom")
		(17 "Dwgs.User" user "User.Drawings")
		(19 "Cmts.User" user "User.Comments")
		(21 "Eco1.User" user "User.Eco1")
		(23 "Eco2.User" user "User.Eco2")
		(25 "Edge.Cuts" user "Board Geometry/Outline")
		(27 "Margin" user)
		(31 "F.CrtYd" user "Package Geometry/Place Bound Top")
		(29 "B.CrtYd" user "Package Geometry/Place Bound Bottom")
		(35 "F.Fab" user "Ref Des/Assembly Top")
		(33 "B.Fab" user "Ref Des/Assembly Bottom")
	)
	(footprint ""
		(layer "F.Cu")
		(at 110.744 -69.85)
		(property "Reference" "R3D23"
			(at 0 0 0)
			(layer "F.SilkS")
			(hide yes)
			(effects
				(font
					(size 1.27 1.27)
				)
			)
		)
		(property "Value" ""
			(at 0 0 0)
			(layer "F.Fab")
			(effects
				(font
					(size 1.27 1.27)
				)
			)
		)
		(duplicate_pad_numbers_are_jumpers no)
		(fp_poly
			(pts
				(xy -0.2794 -0.1016) (xy 0.2794 -0.1016) (xy 0.2794 0.9906) (xy -0.2794 0.9906)
			)
			(stroke
				(width 0)
				(type default)
			)
			(fill no)
			(layer "F.CrtYd")
		)
		(fp_line
			(start -0.2794 -0.1016)
			(end -0.2794 0.9906)
			(stroke
				(width 0.1)
				(type default)
			)
			(layer "F.Fab")
		)
		(fp_line
			(start -0.2794 0.9906)
			(end 0.2794 0.9906)
			(stroke
				(width 0.1)
				(type default)
			)
			(layer "F.Fab")
		)
		(fp_line
			(start 0.2794 -0.1016)
			(end -0.2794 -0.1016)
			(stroke
				(width 0.1)
				(type default)
			)
			(layer "F.Fab")
		)
		(fp_line
			(start 0.2794 0.9906)
			(end 0.2794 -0.1016)
			(stroke
				(width 0.1)
				(type default)
			)
			(layer "F.Fab")
		)
		(pad "1" smd rect
			(at 0 0)
			(size 0.508 0.508)
			(layers "F.Cu" "F.Mask" "F.Paste")
			(net "PVCCIO_CPU1")
		)
		(pad "2" smd rect
			(at 0 0.889)
			(size 0.508 0.508)
			(layers "F.Cu" "F.Mask" "F.Paste")
			(net "PU_CPU1_TXT_AGENT")
		)
		(zone
			(layer "F.Cu")
			(hatch none 0.5)
			(connect_pads
				(clearance 0)
			)
			(min_thickness 0.25)
			(keepout
				(tracks allowed)
				(vias not_allowed)
				(pads allowed)
				(copperpour not_allowed)
				(footprints allowed)
			)
			(placement
				(enabled no)
				(sheetname "")
			)
			(fill
				(thermal_gap 0.5)
				(thermal_bridge_width 0.5)
				(island_removal_mode 0)
			)
			(polygon
				(pts
					(xy 110.49 -69.596) (xy 110.998 -69.596) (xy 110.998 -69.215) (xy 110.49 -69.215)
				)
			)
		)
		(zone
			(layer "F.Cu")
			(hatch none 0.5)
			(connect_pads
				(clearance 0)
			)
			(min_thickness 0.25)
			(keepout
				(tracks not_allowed)
				(vias allowed)
				(pads allowed)
				(copperpour not_allowed)
				(footprints allowed)
			)
			(placement
				(enabled no)
				(sheetname "")
			)
			(fill
				(thermal_gap 0.5)
				(thermal_bridge_width 0.5)
				(island_removal_mode 0)
			)
			(polygon
				(pts
					(xy 110.49 -69.215) (xy 110.998 -69.215) (xy 110.998 -69.596) (xy 110.49 -69.596)
				)
			)
		)
	)
	(footprint ""
		(layer "F.Cu")
		(at 486.3846 -50.2539 180)
		(property "Reference" "C9E5"
			(at 0 0 180)
			(layer "F.SilkS")
			(hide yes)
			(effects
				(font
					(size 1.27 1.27)
				)
			)
		)
		(property "Value" ""
			(at 0 0 180)
			(layer "F.Fab")
			(effects
				(font
					(size 1.27 1.27)
				)
			)
		)
		(duplicate_pad_numbers_are_jumpers no)
		(fp_poly
			(pts
				(xy 0.3048 -0.1016) (xy 0.3048 0.9906) (xy -0.3048 0.9906) (xy -0.3048 -0.1016)
			)
			(stroke
				(width 0)
				(type default)
			)
			(fill no)
			(layer "F.CrtYd")
		)
		(fp_line
			(start 0.3048 0.9906)
			(end 0.3048 -0.1016)
			(stroke
				(width 0.1)
				(type default)
			)
			(layer "F.Fab")
		)
		(fp_line
			(start 0.3048 -0.1016)
			(end -0.3048 -0.1016)
			(stroke
				(width 0.1)
				(type default)
			)
			(layer "F.Fab")
		)
		(fp_line
			(start -0.3048 0.9906)
			(end 0.3048 0.9906)
			(stroke
				(width 0.1)
				(type default)
			)
			(layer "F.Fab")
		)
		(fp_line
			(start -0.3048 -0.1016)
			(end -0.3048 0.9906)
			(stroke
				(width 0.1)
				(type default)
			)
			(layer "F.Fab")
		)
		(pad "1" smd rect
			(at 0 0 180)
			(size 0.508 0.508)
			(layers "F.Cu" "F.Mask" "F.Paste")
			(net "PE_PCH_SPRV_RX_DN")
		)
		(pad "2" smd rect
			(at 0 0.889 180)
			(size 0.508 0.508)
			(layers "F.Cu" "F.Mask" "F.Paste")
			(net "PE_PCH_SPRV_RX_C_DN")
		)
		(zone
			(layer "F.Cu")
			(hatch none 0.5)
			(connect_pads
				(clearance 0)
			)
			(min_thickness 0.25)
			(keepout
				(tracks not_allowed)
				(vias allowed)
				(pads allowed)
				(copperpour not_allowed)
				(footprints allowed)
			)
			(placement
				(enabled no)
				(sheetname "")
			)
			(fill
				(thermal_gap 0.5)
				(thermal_bridge_width 0.5)
				(island_removal_mode 0)
			)
			(polygon
				(pts
					(xy 486.6386 -50.8889) (xy 486.1306 -50.8889) (xy 486.1306 -50.5079) (xy 486.6386 -50.5079)
				)
			)
		)
		(zone
			(layer "F.Cu")
			(hatch none 0.5)
			(connect_pads
				(clearance 0)
			)
			(min_thickness 0.25)
			(keepout
				(tracks allowed)
				(vias not_allowed)
				(pads allowed)
				(copperpour not_allowed)
				(footprints allowed)
			)
			(placement
				(enabled no)
				(sheetname "")
			)
			(fill
				(thermal_gap 0.5)
				(thermal_bridge_width 0.5)
				(island_removal_mode 0)
			)
			(polygon
				(pts
					(xy 486.6386 -50.5079) (xy 486.1306 -50.5079) (xy 486.1306 -50.8889) (xy 486.6386 -50.8889)
				)
			)
		)
	)
	(footprint ""
		(layer "F.Cu")
		(at 1.7018 -134.3152 90)
		(property "Reference" "C1B21"
			(at 0 0 90)
			(layer "F.SilkS")
			(hide yes)
			(effects
				(font
					(size 1.27 1.27)
				)
			)
		)
		(property "Value" ""
			(at 0 0 90)
			(layer "F.Fab")
			(effects
				(font
					(size 1.27 1.27)
				)
			)
		)
		(duplicate_pad_numbers_are_jumpers no)
		(fp_rect
			(start 0.3048 0.9906)
			(end -0.3048 -0.1016)
			(stroke
				(width 0)
				(type default)
			)
			(fill no)
			(layer "F.CrtYd")
		)
		(fp_line
			(start 0.3048 -0.1016)
			(end -0.3048 -0.1016)
			(stroke
				(width 0.1)
				(type default)
			)
			(layer "F.Fab")
		)
		(fp_line
			(start -0.3048 -0.1016)
			(end -0.3048 0.9906)
			(stroke
				(width 0.1)
				(type default)
			)
			(layer "F.Fab")
		)
		(fp_line
			(start 0.3048 0.9906)
			(end 0.3048 -0.1016)
			(stroke
				(width 0.1)
				(type default)
			)
			(layer "F.Fab")
		)
		(fp_line
			(start -0.3048 0.9906)
			(end 0.3048 0.9906)
			(stroke
				(width 0.1)
				(type default)
			)
			(layer "F.Fab")
		)
		(pad "1" smd rect
			(at 0 0 90)
			(size 0.508 0.508)
			(layers "F.Cu" "F.Mask" "F.Paste")
			(net "P5V_STBY")
		)
		(pad "2" smd rect
			(at 0 0.889 90)
			(size 0.508 0.508)
			(layers "F.Cu" "F.Mask" "F.Paste")
			(net "GND")
		)
		(zone
			(layer "F.Cu")
			(hatch none 0.5)
			(connect_pads
				(clearance 0)
			)
			(min_thickness 0.25)
			(keepout
				(tracks not_allowed)
				(vias allowed)
				(pads allowed)
				(copperpour not_allowed)
				(footprints allowed)
			)
			(placement
				(enabled no)
				(sheetname "")
			)
			(fill
				(thermal_gap 0.5)
				(thermal_bridge_width 0.5)
				(island_removal_mode 0)
			)
			(polygon
				(pts
					(xy 2.3368 -134.5692) (xy 1.9558 -134.5692) (xy 1.9558 -134.0612) (xy 2.3368 -134.0612)
				)
			)
		)
		(zone
			(layer "F.Cu")
			(hatch none 0.5)
			(connect_pads
				(clearance 0)
			)
			(min_thickness 0.25)
			(keepout
				(tracks allowed)
				(vias not_allowed)
				(pads allowed)
				(copperpour not_allowed)
				(footprints allowed)
			)
			(placement
				(enabled no)
				(sheetname "")
			)
			(fill
				(thermal_gap 0.5)
				(thermal_bridge_width 0.5)
				(island_removal_mode 0)
			)
			(polygon
				(pts
					(xy 2.3368 -134.5692) (xy 1.9558 -134.5692) (xy 1.9558 -134.0612) (xy 2.3368 -134.0612)
				)
			)
		)
	)
	(footprint ""
		(layer "F.Cu")
		(at 318.543432 -22.740112 -90)
		(property "Reference" "C6F5"
			(at 0 0 270)
			(layer "F.SilkS")
			(hide yes)
			(effects
				(font
					(size 1.27 1.27)
				)
			)
		)
		(property "Value" ""
			(at 0 0 270)
			(layer "F.Fab")
			(effects
				(font
					(size 1.27 1.27)
				)
			)
		)
		(duplicate_pad_numbers_are_jumpers no)
		(fp_poly
			(pts
				(xy -0.4953 -0.2032) (xy 0.4953 -0.2032) (xy 0.4953 1.6002) (xy -0.4953 1.6002)
			)
			(stroke
				(width 0)
				(type default)
			)
			(fill no)
			(layer "F.CrtYd")
		)
		(fp_line
			(start -0.4953 1.6002)
			(end -0.4953 -0.2032)
			(stroke
				(width 0.1)
				(type default)
			)
			(layer "F.Fab")
		)
		(fp_line
			(start 0.4953 1.6002)
			(end -0.4953 1.6002)
			(stroke
				(width 0.1)
				(type default)
			)
			(layer "F.Fab")
		)
		(fp_line
			(start -0.4953 -0.2032)
			(end 0.4953 -0.2032)
			(stroke
				(width 0.1)
				(type default)
			)
			(layer "F.Fab")
		)
		(fp_line
			(start 0.4953 -0.2032)
			(end 0.4953 1.6002)
			(stroke
				(width 0.1)
				(type default)
			)
			(layer "F.Fab")
		)
		(pad "1" smd rect
			(at 0 0 270)
			(size 0.762 0.889)
			(layers "F.Cu" "F.Mask" "F.Paste")
			(net "PVPP_ABC")
		)
		(pad "2" smd rect
			(at 0 1.397 270)
			(size 0.762 0.889)
			(layers "F.Cu" "F.Mask" "F.Paste")
			(net "GND")
		)
		(zone
			(layer "F.Cu")
			(hatch none 0.5)
			(connect_pads
				(clearance 0)
			)
			(min_thickness 0.25)
			(keepout
				(tracks not_allowed)
				(vias allowed)
				(pads allowed)
				(copperpour not_allowed)
				(footprints allowed)
			)
			(placement
				(enabled no)
				(sheetname "")
			)
			(fill
				(thermal_gap 0.5)
				(thermal_bridge_width 0.5)
				(island_removal_mode 0)
			)
			(polygon
				(pts
					(xy 318.098932 -23.121112) (xy 318.098932 -22.359112) (xy 317.590932 -22.359112) (xy 317.590932 -23.121112)
				)
			)
		)
	)
	(footprint ""
		(layer "F.Cu")
		(at 178.981862 -144.998948 90)
		(property "Reference" "R4A8"
			(at 0 0 90)
			(layer "F.SilkS")
			(hide yes)
			(effects
				(font
					(size 1.27 1.27)
				)
			)
		)
		(property "Value" ""
			(at 0 0 90)
			(layer "F.Fab")
			(effects
				(font
					(size 1.27 1.27)
				)
			)
		)
		(duplicate_pad_numbers_are_jumpers no)
		(fp_poly
			(pts
				(xy -0.2794 -0.1016) (xy 0.2794 -0.1016) (xy 0.2794 0.9906) (xy -0.2794 0.9906)
			)
			(stroke
				(width 0)
				(type default)
			)
			(fill no)
			(layer "F.CrtYd")
		)
		(fp_line
			(start 0.2794 -0.1016)
			(end -0.2794 -0.1016)
			(stroke
				(width 0.1)
				(type default)
			)
			(layer "F.Fab")
		)
		(fp_line
			(start -0.2794 -0.1016)
			(end -0.2794 0.9906)
			(stroke
				(width 0.1)
				(type default)
			)
			(layer "F.Fab")
		)
		(fp_line
			(start 0.2794 0.9906)
			(end 0.2794 -0.1016)
			(stroke
				(width 0.1)
				(type default)
			)
			(layer "F.Fab")
		)
		(fp_line
			(start -0.2794 0.9906)
			(end 0.2794 0.9906)
			(stroke
				(width 0.1)
				(type default)
			)
			(layer "F.Fab")
		)
		(pad "1" smd rect
			(at 0 0 90)
			(size 0.508 0.508)
			(layers "F.Cu" "F.Mask" "F.Paste")
			(net "SMB_LAN_STBY_LVC3_SDA")
		)
		(pad "2" smd rect
			(at 0 0.889 90)
			(size 0.508 0.508)
			(layers "F.Cu" "F.Mask" "F.Paste")
			(net "SMB_PIROM_CPU0_SDA")
		)
		(zone
			(layer "F.Cu")
			(hatch none 0.5)
			(connect_pads
				(clearance 0)
			)
			(min_thickness 0.25)
			(keepout
				(tracks allowed)
				(vias not_allowed)
				(pads allowed)
				(copperpour not_allowed)
				(footprints allowed)
			)
			(placement
				(enabled no)
				(sheetname "")
			)
			(fill
				(thermal_gap 0.5)
				(thermal_bridge_width 0.5)
				(island_removal_mode 0)
			)
			(polygon
				(pts
					(xy 179.235862 -144.744948) (xy 179.235862 -145.252948) (xy 179.616862 -145.252948) (xy 179.616862 -144.744948)
				)
			)
		)
		(zone
			(layer "F.Cu")
			(hatch none 0.5)
			(connect_pads
				(clearance 0)
			)
			(min_thickness 0.25)
			(keepout
				(tracks not_allowed)
				(vias allowed)
				(pads allowed)
				(copperpour not_allowed)
				(footprints allowed)
			)
			(placement
				(enabled no)
				(sheetname "")
			)
			(fill
				(thermal_gap 0.5)
				(thermal_bridge_width 0.5)
				(island_removal_mode 0)
			)
			(polygon
				(pts
					(xy 179.616862 -144.744948) (xy 179.616862 -145.252948) (xy 179.235862 -145.252948) (xy 179.235862 -144.744948)
				)
			)
		)
	)
	(footprint ""
		(layer "F.Cu")
		(at 416.56 -56.896 -90)
		(property "Reference" "U8E3"
			(at 0.1778 -2.13487 90)
			(unlocked yes)
			(layer "F.SilkS")
			(effects
				(font
					(size 0.7874 0.5842)
					(thickness 0.1524)
				)
				(justify left)
			)
		)
		(property "Value" ""
			(at 0 0 270)
			(layer "F.Fab")
			(effects
				(font
					(size 1.27 1.27)
				)
			)
		)
		(duplicate_pad_numbers_are_jumpers no)
		(fp_circle
			(center -0.71882 -0.53848)
			(end -0.71882 -0.66548)
			(stroke
				(width 0.254)
				(type default)
			)
			(fill no)
			(layer "F.SilkS")
		)
		(fp_poly
			(pts
				(xy 0.21463 -0.450088) (xy 1.56337 -0.450088) (xy 1.56337 1.75006) (xy 0.21463 1.75006)
			)
			(stroke
				(width 0)
				(type default)
			)
			(fill no)
			(layer "F.CrtYd")
		)
		(fp_line
			(start 0.21463 1.75006)
			(end 0.21463 -0.450088)
			(stroke
				(width 0.1)
				(type default)
			)
			(layer "F.Fab")
		)
		(fp_line
			(start 1.56337 1.75006)
			(end 0.21463 1.75006)
			(stroke
				(width 0.1)
				(type default)
			)
			(layer "F.Fab")
		)
		(fp_line
			(start 0.21463 -0.450088)
			(end 1.56337 -0.450088)
			(stroke
				(width 0.1)
				(type default)
			)
			(layer "F.Fab")
		)
		(fp_line
			(start 1.56337 -0.450088)
			(end 1.56337 1.75006)
			(stroke
				(width 0.1)
				(type default)
			)
			(layer "F.Fab")
		)
		(fp_circle
			(center -0.4699 -0.8382)
			(end -0.4699 -0.9652)
			(stroke
				(width 0.254)
				(type default)
			)
			(fill no)
			(layer "F.Fab")
		)
		(pad "1" smd rect
			(at 0 0 270)
			(size 1.016 0.381)
			(layers "F.Cu" "F.Mask" "F.Paste")
			(net "RST_PLTRST_TOP_SWAP")
		)
		(pad "2" smd rect
			(at 0 0.649986 270)
			(size 1.016 0.381)
			(layers "F.Cu" "F.Mask" "F.Paste")
			(net "FM_BIOS_TOP_SWAP")
		)
		(pad "3" smd rect
			(at 0 1.299972 270)
			(size 1.016 0.381)
			(layers "F.Cu" "F.Mask" "F.Paste")
			(net "GND")
		)
		(pad "4" smd rect
			(at 1.778 1.299972 270)
			(size 1.016 0.381)
			(layers "F.Cu" "F.Mask" "F.Paste")
			(net "FM_BIOS_TOP_SWAP_SPKR_R")
		)
		(pad "5" smd rect
			(at 1.778 0 270)
			(size 1.016 0.381)
			(layers "F.Cu" "F.Mask" "F.Paste")
			(net "P3V3_STBY")
		)
	)
	(footprint ""
		(layer "F.Cu")
		(at 377.5202 -30.629352 90)
		(property "Reference" "C8F15"
			(at -0.8382 -0.67818 90)
			(unlocked yes)
			(layer "F.SilkS")
			(effects
				(font
					(size 0.4064 0.254)
					(thickness 0.1524)
				)
				(justify left)
			)
		)
		(property "Value" ""
			(at 0 0 90)
			(layer "F.Fab")
			(effects
				(font
					(size 1.27 1.27)
				)
			)
		)
		(duplicate_pad_numbers_are_jumpers no)
		(fp_poly
			(pts
				(xy 0.3048 -0.1016) (xy 0.3048 0.9906) (xy -0.3048 0.9906) (xy -0.3048 -0.1016)
			)
			(stroke
				(width 0)
				(type default)
			)
			(fill no)
			(layer "F.CrtYd")
		)
		(fp_line
			(start 0.3048 -0.1016)
			(end -0.3048 -0.1016)
			(stroke
				(width 0.1)
				(type default)
			)
			(layer "F.Fab")
		)
		(fp_line
			(start -0.3048 -0.1016)
			(end -0.3048 0.9906)
			(stroke
				(width 0.1)
				(type default)
			)
			(layer "F.Fab")
		)
		(fp_line
			(start 0.3048 0.9906)
			(end 0.3048 -0.1016)
			(stroke
				(width 0.1)
				(type default)
			)
			(layer "F.Fab")
		)
		(fp_line
			(start -0.3048 0.9906)
			(end 0.3048 0.9906)
			(stroke
				(width 0.1)
				(type default)
			)
			(layer "F.Fab")
		)
		(pad "1" smd rect
			(at 0 0 90)
			(size 0.508 0.508)
			(layers "F.Cu" "F.Mask" "F.Paste")
			(net "SATA6G_S0_RX_DN")
		)
		(pad "2" smd rect
			(at 0 0.889 90)
			(size 0.508 0.508)
			(layers "F.Cu" "F.Mask" "F.Paste")
			(net "P3E_PCH_M2_SATA6G_RX_R_DN")
		)
		(zone
			(layer "F.Cu")
			(hatch none 0.5)
			(connect_pads
				(clearance 0)
			)
			(min_thickness 0.25)
			(keepout
				(tracks allowed)
				(vias not_allowed)
				(pads allowed)
				(copperpour not_allowed)
				(footprints allowed)
			)
			(placement
				(enabled no)
				(sheetname "")
			)
			(fill
				(thermal_gap 0.5)
				(thermal_bridge_width 0.5)
				(island_removal_mode 0)
			)
			(polygon
				(pts
					(xy 377.7742 -30.375352) (xy 377.7742 -30.883352) (xy 378.1552 -30.883352) (xy 378.1552 -30.375352)
				)
			)
		)
		(zone
			(layer "F.Cu")
			(hatch none 0.5)
			(connect_pads
				(clearance 0)
			)
			(min_thickness 0.25)
			(keepout
				(tracks not_allowed)
				(vias allowed)
				(pads allowed)
				(copperpour not_allowed)
				(footprints allowed)
			)
			(placement
				(enabled no)
				(sheetname "")
			)
			(fill
				(thermal_gap 0.5)
				(thermal_bridge_width 0.5)
				(island_removal_mode 0)
			)
			(polygon
				(pts
					(xy 378.1552 -30.375352) (xy 378.1552 -30.883352) (xy 377.7742 -30.883352) (xy 377.7742 -30.375352)
				)
			)
		)
	)
)
